FILE_TYPE = CONNECTIVITY;
{Allegro Design Entry HDL 16.6-p007 (v16-6-112F) 10/10/2012}
"PAGE_NUMBER" = 97;
0"NC";
1"PVCCIO_CPU0\g";
2"PVCCIO_CPU0\g";
3"PVCCIO_CPU1\g";
4"GND\g";
5"PVCCIO_CPU0\g";
6"H_CPU0_FAST_WAKE_N";
7"PU_CPU0_TSC_SYNC";
8"PU_CPU1_TSC_SYNC";
9"PD_CPU1_MCP01_DMON";
10"PD_CPU0_MCP01_DMON";
11"H_CPU1_FAST_WAKE_N";
%"RES"
"1","(-2000,4225)","0","mstr_discrete","I33";
;
TOLERANCE"5%"
PART_NUMBER"G21497-005"
VALUE"0.0"
PACK_TYPE"0402"
MATERIAL"CHIP"
WATTAGE"1/16W"
LOCATION"R3D18"
BOM_COST"PROC_SIDEBAND"
CDS_LIB"mstr_discrete"
CDS_SEC"1"
$SEC"1"
CDS_LOCATION"R3D18"
ROOM"PROC_SIDEBAND";
"B"
$PN"2"11;
"A"
$PN"1"6;
%"PVCCIO_CPU0"
"1","(-2700,4775)","0","mstr_symbols","I41";
;
VOLTAGE"1.1V"
CDS_LIB"mstr_symbols"
BODY_TYPE"PLUMBING"
HDL_POWER"PVCCIO_CPU0";
"G\NAC"1;
%"RES"
"2","(-2700,4525)","0","mstr_discrete","I42";
;
LOCATION"R4R4"
PART_NUMBER"G21796-009"
VALUE"150.0"
TOLERANCE"1%"
PACK_TYPE"0402"
MATERIAL"CHIP"
WATTAGE"1/16W"
CDS_LIB"mstr_discrete"
CDS_SEC"1"
$SEC"1"
CDS_LOCATION"R4R4"
ROOM"PROC_SIDEBAND";
"A"
$PN"1"1;
"B"
$PN"2"6;
%"RES"
"2","(-1200,4525)","0","mstr_discrete","I44";
;
PART_NUMBER"G21796-009"
LOCATION"R7P20"
VALUE"150.0"
TOLERANCE"1%"
WATTAGE"1/16W"
PACK_TYPE"0402"
MATERIAL"CHIP"
CDS_LIB"mstr_discrete"
CDS_SEC"1"
$SEC"1"
CDS_LOCATION"R7P20"
ROOM"PROC_SIDEBAND";
"A"
$PN"1"5;
"B"
$PN"2"11;
%"PVCCIO_CPU0"
"1","(-3100,1625)","0","mstr_symbols","I71";
;
VOLTAGE"1.1V"
CDS_LIB"mstr_symbols"
BODY_TYPE"PLUMBING"
HDL_POWER"PVCCIO_CPU0";
"G\NAC"2;
%"RES"
"1","(-2625,1425)","0","mstr_discrete","I72";
;
CDS_SEC"1"
LOCATION"R4P21"
PART_NUMBER"G21796-294"
VALUE"240"
TOLERANCE"1.0%"
PACK_TYPE"0402"
WATTAGE"1/16W"
MATERIAL"CHIP"
SEC_TYPE"0402"
CDS_LIB"mstr_discrete"
BOM_COST"PROC_SIDEBAND"
SEC"1"
CDS_LOCATION"R4P21"
ROOM"PROC_SIDEBAND";
"B"
$PN"2"7;
"A"
$PN"1"2;
%"RES"
"1","(-2600,800)","0","mstr_discrete","I76";
;
CDS_SEC"1"
LOCATION"R4C10"
PART_NUMBER"G21796-294"
VALUE"240"
TOLERANCE"1.0%"
PACK_TYPE"0402"
MATERIAL"CHIP"
WATTAGE"1/16W"
SEC_TYPE"0402"
CDS_LIB"mstr_discrete"
BOM_COST"PROC_SIDEBAND"
SEC"1"
CDS_LOCATION"R4C10"
ROOM"PROC_SIDEBAND";
"B"
$PN"2"8;
"A"
$PN"1"3;
%"PVCCIO_CPU1"
"1","(-3075,1000)","0","mstr_symbols","I78";
;
VOLTAGE"1.1V"
CDS_LIB"mstr_symbols"
BODY_TYPE"PLUMBING"
HDL_POWER"PVCCIO_CPU1";
"G\NAC"3;
%"RES"
"1","(-2375,3175)","0","mstr_discrete","I80";
;
CDS_SEC"1"
PART_NUMBER"G21796-016"
LOCATION"R4P5"
VALUE"10.0K"
TOLERANCE"1%"
PACK_TYPE"0402"
MATERIAL"CHIP"
WATTAGE"1/16W"
CDS_LIB"mstr_discrete"
SEC_TYPE"0402"
SEC"1"
CDS_LOCATION"R4P5"
ROOM"CPU0";
"B"
$PN"2"10;
"A"
$PN"1"4;
%"RES"
"1","(-2375,2825)","0","mstr_discrete","I81";
;
CDS_SEC"1"
LOCATION"R7P13"
PART_NUMBER"G21796-016"
VALUE"10.0K"
TOLERANCE"1%"
PACK_TYPE"0402"
MATERIAL"CHIP"
WATTAGE"1/16W"
CDS_LIB"mstr_discrete"
SEC_TYPE"0402"
SEC"1"
CDS_LOCATION"R7P13"
ROOM"CPU1";
"B"
$PN"2"9;
"A"
$PN"1"4;
%"GND"
"1","(-3075,2425)","0","mstr_symbols","I82";
;
VOLTAGE"0.0V"
SIZE"1B"
CDS_LIB"mstr_symbols"
BODY_TYPE"PLUMBING"
HDL_POWER"GND";
"A\NAC"4;
%"PVCCIO_CPU0"
"1","(-1200,4775)","0","mstr_symbols","I85";
;
VOLTAGE"1.1V"
CDS_LIB"mstr_symbols"
BODY_TYPE"PLUMBING"
HDL_POWER"PVCCIO_CPU0";
"G\NAC"5;
END.
